G04 ================== begin FILE IDENTIFICATION RECORD ==================*
G04 Layout Name:  12523-1.brd*
G04 Film Name:    L4*
G04 File Format:  Gerber RS274X*
G04 File Origin:  Cadence Allegro 16.2-s031*
G04 Origin Date:  Fri Oct 19 14:59:14 2012*
G04 *
G04 Layer:  VIA CLASS/BOTTOM*
G04 Layer:  PIN/BOTTOM*
G04 Layer:  ETCH/BOTTOM*
G04 Layer:  DRAWING FORMAT/LAYER_PCB_STORY*
G04 Layer:  DRAWING FORMAT/LAYER_L4*
G04 *
G04 Offset:    (0.00 0.00)*
G04 Mirror:    No*
G04 Mode:      Positive*
G04 Rotation:  0*
G04 FullContactRelief:  No*
G04 UndefLineWidth:     6.00*
G04 ================== end FILE IDENTIFICATION RECORD ====================*
%FSLAX35Y35*MOIN*%
%IR0*IPPOS*OFA0.00000B0.00000*MIA0B0*SFA1.00000B1.00000*%
%ADD10C,.01*%
%ADD19C,.053*%
%ADD17R,.197X.032*%
%ADD13C,.028*%
%ADD18C,.057*%
%ADD12R,.05X.05*%
%ADD14R,.001X.001*%
%ADD16R,.248X.165*%
%ADD15R,.248X.372*%
%ADD11C,.355*%
%ADD20C,.02*%
%ADD21C,.03*%
%ADD22C,.04*%
%ADD23C,.006*%
%ADD24C,.0055*%
%ADD29C,.05204*%
%ADD25C,.08104*%
%ADD26C,.07704*%
%ADD28C,.05806*%
%ADD27C,.18206*%
G75*
%LPD*%
G75*
G36*
G01X599010Y85203D02*
G03X599534Y80927I-2908J-2526D01*
G01X599548Y80955D01*
X599849Y81261D01*
G02X600532Y80978I283J-283D01*
G01Y78363D01*
X600414Y78310D01*
G03X603602I1594J-3507D01*
G01X603484Y78363D01*
Y80883D01*
X613037Y90436D01*
X613104Y90446D01*
G03X614307Y95106I-357J2577D01*
G01X614226Y95166D01*
Y205862D01*
X608112Y211976D01*
X604670D01*
G02X604314Y212559I0J400D01*
G03X597104I-3605J1850D01*
G02X596748Y211976I-356J-183D01*
G01X596023D01*
X594628Y213372D01*
X594653Y213481D01*
Y213482D01*
X594658Y213504D01*
G03X588874Y218022I-3949J905D01*
G01X588831Y218000D01*
X582587D01*
X582544Y218022D01*
G03X578874I-1835J-3613D01*
G01X578831Y218000D01*
X572587D01*
X572544Y218022D01*
G03X568874I-1835J-3613D01*
G01X568831Y218000D01*
X568500D01*
X566750Y216250D01*
Y215271D01*
X566746Y215250D01*
Y215246D01*
X566742Y215226D01*
G03X566735Y213624I3967J-818D01*
G01X566739Y213605D01*
Y213603D01*
X566750Y213547D01*
Y205271D01*
X566746Y205250D01*
Y205246D01*
X566742Y205226D01*
G03X566735Y203624I3967J-818D01*
G01X566739Y203605D01*
Y203603D01*
X566750Y203547D01*
Y200750D01*
X554000Y188000D01*
X417500D01*
X410564Y194936D01*
X-32902D01*
X-33302Y195336D01*
Y231336D01*
X-32702Y231936D01*
X-12538D01*
X-12366Y232108D01*
Y234653D01*
X-12575Y234862D01*
X-32628D01*
X-33202Y235436D01*
Y271336D01*
X-32609Y271929D01*
X-12610D01*
X-12463Y272076D01*
Y274708D01*
X-12616Y274861D01*
X-32727D01*
X-33202Y275336D01*
Y288394D01*
X-32557Y289039D01*
X890D01*
X3398Y291547D01*
Y297936D01*
X898Y300436D01*
X-3602D01*
X-4102Y300936D01*
Y302936D01*
X-3602Y303436D01*
X50398D01*
X60898Y313936D01*
Y372936D01*
X68398Y380436D01*
X497398D01*
X500398Y377436D01*
Y344436D01*
X535398Y309436D01*
X571898D01*
X574398Y311936D01*
Y319936D01*
X576398Y321936D01*
X612398D01*
X614898Y324436D01*
Y344436D01*
X613898Y345436D01*
X534398D01*
X528898Y350936D01*
Y382436D01*
X541898Y395436D01*
X613398D01*
X616398Y398436D01*
Y407436D01*
X617398Y408436D01*
X621898D01*
X622898Y409436D01*
Y416602D01*
X616064Y423436D01*
X519998D01*
X504498Y407936D01*
X45834D01*
X26898Y389000D01*
Y360936D01*
X16898Y350936D01*
X3434D01*
X434Y353936D01*
X-9102D01*
X-10102Y354936D01*
Y361936D01*
X-9602Y362436D01*
X-3609D01*
X-3601Y362435D01*
G03X3398Y368936I480J6501D01*
G01Y467936D01*
X4898Y469436D01*
X635898D01*
X637256Y468078D01*
Y388044D01*
X628091Y381936D01*
X545898D01*
G03X538898Y374936I0J-7000D01*
G01Y357436D01*
G03X545898Y350436I7000J0D01*
G01X627981D01*
X637183Y344334D01*
Y321000D01*
X636183Y320000D01*
X621500D01*
X617500Y316000D01*
Y133000D01*
X621500Y129000D01*
X636000D01*
X637183Y127817D01*
Y3894D01*
X636492Y3203D01*
X4381D01*
X3479Y4105D01*
Y74479D01*
X3500Y74500D01*
Y78500D01*
X4000Y79000D01*
X38000D01*
X54564Y62436D01*
X547960D01*
X593000Y107476D01*
Y119500D01*
X600500Y127000D01*
X606500D01*
X608841Y129341D01*
G02X609524Y129058I283J-283D01*
G01Y102563D01*
X609372Y102525D01*
G03X608443Y97915I628J-2525D01*
G01X608524Y97855D01*
Y94112D01*
X599595Y85183D01*
G02X599010Y85203I-283J283D01*
G37*
G36*
G01X608000Y162000D02*
X589000Y143000D01*
Y106500D01*
X546936Y64436D01*
X56500D01*
X38936Y82000D01*
X5898D01*
X3398Y84500D01*
Y110436D01*
X-921Y114755D01*
X-30850D01*
X-30866Y114772D01*
X-32938D01*
X-33302Y115136D01*
Y151236D01*
X-32642Y151896D01*
X-12594D01*
X-12326Y152164D01*
Y154539D01*
X-12645Y154858D01*
X-33024D01*
X-33302Y155136D01*
Y191436D01*
X-32778Y191960D01*
X409000D01*
X415960Y185000D01*
X555500D01*
X567500Y197000D01*
X605500D01*
X608000Y194500D01*
Y162000D01*
G37*
G36*
G01X36000Y387998D02*
X36800Y388798D01*
X36804D01*
X37002Y388996D01*
X40562D01*
X40566Y389000D01*
X42500D01*
X53436Y399936D01*
X510262D01*
X523962Y413636D01*
X613198D01*
X613898Y412936D01*
Y399436D01*
X611898Y397436D01*
X540398D01*
X526398Y383436D01*
Y350436D01*
X533898Y342936D01*
X609398D01*
X611148Y341186D01*
Y326186D01*
X609898Y324936D01*
X575398D01*
X571898Y321436D01*
Y313436D01*
X570898Y312436D01*
X536898D01*
X503398Y345936D01*
Y380936D01*
X501398Y382936D01*
X66898D01*
X58898Y374936D01*
Y315936D01*
X48563Y305601D01*
X-17483D01*
X-17499Y305617D01*
X-31020D01*
X-31265Y305862D01*
Y308534D01*
X-31081Y308718D01*
X-17690D01*
X-17556Y308852D01*
Y310554D01*
X-17647Y310645D01*
X-31106D01*
X-31265Y310804D01*
Y313269D01*
X-30873Y313661D01*
X-7228D01*
X-7218Y313660D01*
G03X-6662I278J2587D01*
G01X-6652Y313661D01*
X-1607D01*
X-427Y314841D01*
X4398D01*
X10743Y321186D01*
X34148D01*
X45398Y332436D01*
Y374436D01*
X36000Y383834D01*
Y387998D01*
G37*
%LPC*%
G75*
G36*
G01X557473Y234061D02*
X564888Y241476D01*
X567048D01*
G03X567376Y242104I-1J400D01*
G02X574042I3333J2305D01*
G03X574370Y241476I329J-228D01*
G01X575688D01*
X576995Y242783D01*
X576946Y242906D01*
G02X579206Y240646I3763J1503D01*
G01X579083Y240695D01*
X577797Y239409D01*
X579083Y238123D01*
X579206Y238172D01*
G02X576946Y235912I1503J-3763D01*
G01X576995Y236035D01*
X576256Y236774D01*
X574704D01*
G03X574345Y236197I0J-400D01*
G02X567221Y236472I-3636J-1788D01*
G01X567249Y236519D01*
Y236774D01*
X566862D01*
X563614Y233526D01*
X563699Y233391D01*
G02X559738Y230085I-2199J-1391D01*
G03X559139Y230018I-270J-295D01*
G02X557373Y234075I-2139J1482D01*
G01X557473Y234061D01*
G37*
G36*
G01X25118Y219438D02*
X21181D01*
G02X14242Y226378I1J6940D01*
G01Y246063D01*
G02X21181Y253002I6939J0D01*
G01X25118D01*
G02X32058Y246063I1J-6939D01*
G01Y226378D01*
G02X25118Y219438I-6940J0D01*
G37*
G54D29*
X537136Y326402D03*
G54D25*
X600709Y286929D03*
X590709D03*
X600709Y224409D03*
X590709D03*
X600709Y234409D03*
X590709D03*
X600709Y256929D03*
X590709D03*
X600709Y266929D03*
X590709D03*
X600709Y276929D03*
X590709D03*
X600709Y244409D03*
X590709D03*
X580709Y286929D03*
X570709D03*
X580709Y224409D03*
X570709D03*
X580709Y256929D03*
X570709D03*
X580709Y266929D03*
X570709D03*
X580709Y276929D03*
X570709D03*
Y161889D03*
X580709D03*
X570709Y191889D03*
X580709D03*
X570709Y181889D03*
X580709D03*
X570709Y171889D03*
X580709D03*
X590709Y161889D03*
X600709D03*
X590709Y191889D03*
X600709D03*
X590709Y181889D03*
X600709D03*
X590709Y171889D03*
X600709D03*
G54D26*
X596102Y66929D03*
G54D28*
X599055Y90551D03*
Y59055D03*
G54D27*
X600709Y311909D03*
%LPD*%
G75*
G54D10*
X-23621Y15748D03*
Y937008D03*
X599055Y59055D03*
Y90551D03*
X600709Y136909D03*
Y311909D03*
X1312285Y15747D03*
G54D20*
G01X-4246Y-109426D02*
Y-189426D01*
G01D02*
X1290354D01*
G01X-4246Y-144926D02*
X1290354D01*
G01X-8246Y-93426D02*
G02I-12000J0D01*
G01X-13396D02*
G02I-6850J0D01*
G01X-20246Y-109426D02*
Y-77426D01*
G01X-4246Y-93426D02*
X-36246D01*
G01X-4246Y-109426D02*
X1290354D01*
G01X502854D02*
Y-189426D01*
G01X570709Y157637D02*
Y161889D01*
G01D02*
X574961D01*
G01X566457D02*
X570709D01*
G01D02*
Y166141D01*
G01X576457Y161889D02*
X580709D01*
G01X570709Y191889D02*
X574961D01*
G01X566457D02*
X570709D01*
G01D02*
Y196141D01*
G01Y187637D02*
Y191889D01*
G01X576457D02*
X580709D01*
G01X570709Y181889D02*
X574961D01*
G01X566457D02*
X570709D01*
G01D02*
Y186141D01*
G01Y177637D02*
Y181889D01*
G01X576457D02*
X580709D01*
G01X570709Y171889D02*
X574961D01*
G01X566457D02*
X570709D01*
G01D02*
Y176141D01*
G01Y167637D02*
Y171889D01*
G01X576457D02*
X580709D01*
G01X570709Y272677D02*
Y276929D01*
G01Y266929D02*
X574961D01*
G01X566457D02*
X570709D01*
G01D02*
Y271181D01*
G01Y262677D02*
Y266929D01*
G01X576457D02*
X580709D01*
G01X570709Y256929D02*
X574961D01*
G01X566457D02*
X570709D01*
G01D02*
Y261181D01*
G01Y252677D02*
Y256929D01*
G01X576457D02*
X580709D01*
G01X570709Y276929D02*
X574961D01*
G01X566457D02*
X570709D01*
G01D02*
Y281181D01*
G01X576457Y276929D02*
X580709D01*
G01X570709Y286929D02*
X574961D01*
G01X566457D02*
X570709D01*
G01D02*
Y291181D01*
G01Y282677D02*
Y286929D01*
G01X576457D02*
X580709D01*
G01Y157637D02*
Y161889D01*
G01X590709Y157637D02*
Y161889D01*
G01X600709Y157637D02*
Y161889D01*
G01X580709D02*
X584961D01*
G01X580709D02*
Y166141D01*
G01Y191889D02*
X584961D01*
G01X580709D02*
Y196141D01*
G01Y187637D02*
Y191889D01*
G01Y181889D02*
X584961D01*
G01X580709D02*
Y186141D01*
G01Y177637D02*
Y181889D01*
G01Y171889D02*
X584961D01*
G01X580709D02*
Y176141D01*
G01Y167637D02*
Y171889D01*
G01X590709Y161889D02*
X594961D01*
G01X586457D02*
X590709D01*
G01D02*
Y166141D01*
G01X600709Y161889D02*
X604961D01*
G01X596457D02*
X600709D01*
G01D02*
Y166141D01*
G01X590709Y191889D02*
X594961D01*
G01X586457D02*
X590709D01*
G01D02*
Y196141D01*
G01Y187637D02*
Y191889D01*
G01X600709D02*
X604961D01*
G01X596457D02*
X600709D01*
G01D02*
Y196141D01*
G01Y187637D02*
Y191889D01*
G01X590709Y181889D02*
X594961D01*
G01X586457D02*
X590709D01*
G01D02*
Y186141D01*
G01Y177637D02*
Y181889D01*
G01X600709D02*
X604961D01*
G01X596457D02*
X600709D01*
G01D02*
Y186141D01*
G01Y177637D02*
Y181889D01*
G01X590709Y171889D02*
X594961D01*
G01X586457D02*
X590709D01*
G01D02*
Y176141D01*
G01Y167637D02*
Y171889D01*
G01X600709D02*
X604961D01*
G01X596457D02*
X600709D01*
G01D02*
Y176141D01*
G01Y167637D02*
Y171889D01*
G01Y214409D02*
X604961D01*
G01X596457D02*
X600709D01*
G01D02*
Y218661D01*
G01X580709Y272677D02*
Y276929D01*
G01Y266929D02*
X584961D01*
G01X580709D02*
Y271181D01*
G01Y262677D02*
Y266929D01*
G01Y256929D02*
X584961D01*
G01X580709D02*
Y261181D01*
G01Y252677D02*
Y256929D01*
G01X590709Y244409D02*
X594961D01*
G01X586457D02*
X590709D01*
G01D02*
Y248661D01*
G01Y240157D02*
Y244409D01*
G01Y272677D02*
Y276929D01*
G01X600709Y272677D02*
Y276929D01*
G01X590709Y266929D02*
X594961D01*
G01X586457D02*
X590709D01*
G01D02*
Y271181D01*
G01Y262677D02*
Y266929D01*
G01X600709D02*
X604961D01*
G01X596457D02*
X600709D01*
G01D02*
Y271181D01*
G01Y262677D02*
Y266929D01*
G01X590709Y256929D02*
X594961D01*
G01X586457D02*
X590709D01*
G01D02*
Y261181D01*
G01Y252677D02*
Y256929D01*
G01X600709D02*
X604961D01*
G01X596457D02*
X600709D01*
G01D02*
Y261181D01*
G01Y252677D02*
Y256929D01*
G01Y234409D02*
X604961D01*
G01X596457D02*
X600709D01*
G01D02*
Y238661D01*
G01Y230157D02*
Y234409D01*
G01X590709Y224409D02*
X594961D01*
G01X586457D02*
X590709D01*
G01D02*
Y228661D01*
G01Y220157D02*
Y224409D01*
G01X580709Y276929D02*
X584961D01*
G01X580709D02*
Y281181D01*
G01Y286929D02*
X584961D01*
G01X580709D02*
Y291181D01*
G01Y282677D02*
Y286929D01*
G01X590709Y276929D02*
X594961D01*
G01X586457D02*
X590709D01*
G01D02*
Y281181D01*
G01X600709Y276929D02*
X604961D01*
G01X596457D02*
X600709D01*
G01D02*
Y281181D01*
G01X590709Y286929D02*
X594961D01*
G01X586457D02*
X590709D01*
G01D02*
Y291181D01*
G01Y282677D02*
Y286929D01*
G01X600709D02*
X604961D01*
G01X596457D02*
X600709D01*
G01D02*
Y291181D01*
G01Y282677D02*
Y286929D01*
G01X640354Y-109426D02*
Y-189426D01*
G01X755354Y-109426D02*
Y-189426D01*
G01X922854Y-109426D02*
Y-189426D01*
G01X1092854Y-109426D02*
Y-189426D01*
G01X1290354Y-109426D02*
Y-189426D01*
G01X1318354Y-93426D02*
G02I-12000J0D01*
G01X1313204D02*
G02I-6850J0D01*
G01X1306354Y-109426D02*
Y-77426D01*
G01X1322354Y-93426D02*
X1290354D01*
G54D11*
X30157Y61023D03*
Y415354D03*
X498661Y23622D03*
X589212Y448818D03*
G54D21*
G01X-26055Y302202D02*
X-2948D01*
G01X-26055Y337202D02*
X-7102D01*
G01X-26055Y347202D02*
X-6602D01*
G01Y357202D02*
X-26055D01*
G54D12*
X-23622Y62794D03*
Y916269D03*
X1297695Y58466D03*
G54D22*
G01X20898Y325436D02*
X9116D01*
X2334Y318654D01*
G01X536398Y418936D02*
X522898D01*
X508398Y404436D01*
X51476D01*
X51472Y404434D01*
X39236Y392198D01*
X35676D01*
X35478Y392000D01*
X35474D01*
X32000Y388526D01*
Y382000D01*
X41398Y372602D01*
Y335436D01*
X31398Y325436D01*
X20898D01*
G01X617798Y413000D02*
Y415012D01*
X613874Y418936D01*
X536398D01*
G54D13*
X6419Y116482D03*
X-3350Y117504D03*
X6419Y126482D03*
X-3581D03*
X6419Y136482D03*
X-3581D03*
X6419Y146482D03*
X-3581D03*
X6419Y156482D03*
X-3581D03*
X-2602Y206936D03*
X7398D03*
X-2602Y216936D03*
X7398D03*
X6419Y166482D03*
X-3581D03*
Y176482D03*
X6419D03*
X-2602Y226936D03*
X7398D03*
X-2602Y246936D03*
X7398D03*
X-2602Y236936D03*
X7398D03*
Y256936D03*
X-2602D03*
Y266936D03*
X7398D03*
Y276936D03*
X-2602D03*
X7398Y286936D03*
X3398Y326936D03*
X-2948Y302202D03*
X-2602Y316436D03*
X-7102Y327202D03*
X-6940Y316247D03*
X2334Y318654D03*
X1494Y343705D03*
X5694D03*
X-6602Y347202D03*
X-7102Y337202D03*
X-6602Y357202D03*
X6898Y387436D03*
X6398Y369936D03*
X-2722Y341000D03*
X1635Y347764D03*
X6898Y445436D03*
Y465436D03*
X16419Y6482D03*
Y26482D03*
X36419Y6482D03*
Y26482D03*
X56419Y46482D03*
X16419Y86482D03*
X36419D03*
X56419Y66482D03*
Y86482D03*
X26419Y116482D03*
X16419D03*
X26419Y126482D03*
X16419D03*
X26419Y136482D03*
X16419D03*
X26419Y146482D03*
X16419D03*
X26419Y156482D03*
X16419D03*
X36419Y126482D03*
X16419Y106482D03*
X36419D03*
Y146482D03*
X56419Y126482D03*
Y106482D03*
Y146482D03*
X46898Y152936D03*
Y117936D03*
X27398Y206936D03*
X17398D03*
X27398Y216936D03*
X17398D03*
X26419Y186482D03*
X16419D03*
X26419Y166482D03*
X16419D03*
Y176482D03*
X26419D03*
X36419Y186482D03*
Y166482D03*
X56419Y186482D03*
Y166482D03*
X57398Y206936D03*
X37398D03*
X47398Y214936D03*
X46898Y182936D03*
X17398Y256936D03*
X27398D03*
Y266936D03*
X17398D03*
X57398Y226936D03*
X36769D03*
X57398Y246936D03*
Y266936D03*
X36769Y246936D03*
X37398Y266936D03*
X48398Y274936D03*
X17398Y276936D03*
X27398Y286936D03*
X17398D03*
X27398Y276936D03*
X10000Y332000D03*
X57398Y286936D03*
X37398D03*
X64398Y304436D03*
X26500Y330436D03*
X20898Y325436D03*
X49398Y326436D03*
X20398Y309936D03*
X30923Y335665D03*
X25500Y353000D03*
X25000Y343000D03*
X33986Y362933D03*
X26723Y335665D03*
X22000Y374500D03*
X34898Y344936D03*
X57398Y348682D03*
X52705Y348626D03*
X48325Y348514D03*
X62398Y338436D03*
X37500Y386500D03*
X22000Y387500D03*
X61898Y358936D03*
X14000Y336000D03*
X53398Y388936D03*
X62000Y442500D03*
X60052Y394674D03*
X35830Y442464D03*
X55352Y394674D03*
X51094Y394478D03*
X55500Y417000D03*
X19898Y465436D03*
X39898D03*
X76419Y46482D03*
X116419D03*
X96419D03*
X76000Y32000D03*
X76419Y66482D03*
Y86482D03*
X116419Y66482D03*
X96419D03*
X116419Y86482D03*
X96419D03*
X73000Y94500D03*
X76419Y126482D03*
Y106482D03*
Y146482D03*
X116419Y126482D03*
Y106482D03*
X96419Y126482D03*
Y106482D03*
X116419Y146482D03*
X96419D03*
X76419Y186482D03*
Y166482D03*
X77398Y206936D03*
X116419Y186482D03*
Y166482D03*
X96419Y186482D03*
Y166482D03*
X117398Y206936D03*
X97398D03*
X77398Y226936D03*
Y246936D03*
Y266936D03*
X117398Y226936D03*
X97398D03*
X117398Y246936D03*
X97398D03*
Y266936D03*
X116398D03*
X77398Y286936D03*
X86398Y303936D03*
X97398Y286936D03*
X116398D03*
X114398Y308936D03*
X77898Y338436D03*
X78398Y358436D03*
X115330Y337964D03*
X96398Y337936D03*
X115330Y377964D03*
Y357964D03*
X95330Y377964D03*
Y357964D03*
X78398Y371936D03*
X105330Y442964D03*
X85330D03*
X75500Y417500D03*
X115330Y417964D03*
X95330D03*
X67398Y416936D03*
X91500Y465500D03*
X117500D03*
X67830Y465464D03*
X136419Y6482D03*
Y46482D03*
X176419Y6482D03*
Y26482D03*
X156419Y6482D03*
Y26482D03*
X176419Y46482D03*
X156419D03*
X136419Y66482D03*
Y86482D03*
X176419Y66482D03*
X156419D03*
X176419Y86482D03*
X156419D03*
X136419Y126482D03*
Y106482D03*
Y146482D03*
X176419Y126482D03*
Y106482D03*
X156419Y126482D03*
Y106482D03*
X176419Y146482D03*
X156419D03*
X136419Y186482D03*
Y166482D03*
X137398Y206936D03*
X176419Y186482D03*
Y166482D03*
X156419Y186482D03*
Y166482D03*
X177398Y206436D03*
X157398Y206936D03*
X137398Y226936D03*
Y246936D03*
Y266936D03*
X177398Y226936D03*
X157398D03*
X177398Y246936D03*
Y266936D03*
X157398Y246936D03*
Y266936D03*
X137398Y286936D03*
X177398D03*
X157398D03*
X135330Y337964D03*
Y377964D03*
Y357964D03*
X175330Y337964D03*
X155330D03*
X175330Y377964D03*
Y357964D03*
X155330Y377964D03*
Y357964D03*
X132000Y442500D03*
X135330Y417964D03*
X175500Y442000D03*
X175330Y417964D03*
X155000Y442000D03*
X155330Y417964D03*
X139898Y465436D03*
X159898D03*
X196419Y6482D03*
Y26482D03*
Y46482D03*
X236419Y6482D03*
Y26482D03*
X216419Y6482D03*
Y26482D03*
X236419Y46482D03*
X216419D03*
X196419Y66482D03*
Y86482D03*
X236419Y66482D03*
X216419D03*
X236419Y86482D03*
X216419D03*
X196419Y126482D03*
Y106482D03*
Y146482D03*
X236419Y126482D03*
Y106482D03*
X216419Y126482D03*
Y106482D03*
X236419Y146482D03*
X216419D03*
X189398Y115936D03*
X196419Y186482D03*
Y166482D03*
X197398Y206436D03*
X236419Y186482D03*
Y166482D03*
X216419Y186482D03*
Y166482D03*
X217398Y206436D03*
X197398Y226936D03*
Y246936D03*
Y266936D03*
X217398Y226936D03*
Y246936D03*
Y266936D03*
X197398Y286936D03*
X217398D03*
X195330Y337964D03*
Y377964D03*
Y357964D03*
X235330Y337964D03*
X215330D03*
X235330Y377964D03*
Y357964D03*
X215330Y377964D03*
Y357964D03*
X196000Y442500D03*
X195330Y417964D03*
X235830Y442464D03*
X235330Y417964D03*
X215830Y442464D03*
X215330Y417964D03*
X208398Y433436D03*
X179898Y465436D03*
X219898D03*
X199898D03*
X256419Y6482D03*
Y26482D03*
X276419Y6482D03*
Y26482D03*
X256419Y46482D03*
X276419D03*
X248898Y35936D03*
X256419Y66482D03*
X273500Y66500D03*
X256419Y86482D03*
X274500Y86500D03*
X256419Y126482D03*
X276419D03*
X256419Y106482D03*
X274500Y106500D03*
X256419Y146482D03*
X276419D03*
X237398Y206436D03*
X256419Y186482D03*
X275500Y186500D03*
X251500Y166500D03*
X276419Y166482D03*
X257398Y206436D03*
X277398D03*
X237398Y226936D03*
Y246936D03*
Y266936D03*
X257398Y226936D03*
X277398D03*
X257398Y246936D03*
X277398D03*
X257398Y266936D03*
X277398D03*
X247898Y234936D03*
X237398Y286936D03*
X257398D03*
X279398D03*
X282398Y312436D03*
X255330Y337964D03*
X275330D03*
X255330Y377964D03*
X275330D03*
X255330Y357964D03*
X275330D03*
X255830Y442464D03*
X275830D03*
X255330Y417964D03*
X275330D03*
X239898Y465436D03*
X279898D03*
X259898D03*
X296419Y6482D03*
Y26482D03*
Y46482D03*
X316419Y6482D03*
Y26482D03*
X336419Y6482D03*
Y26482D03*
X316419Y46482D03*
X336419D03*
X302000Y67000D03*
X301000Y86500D03*
X316419Y66482D03*
X336419D03*
X316419Y86482D03*
X336419D03*
X296419Y126482D03*
X300000Y106500D03*
X296419Y146482D03*
X316419Y126482D03*
X336419D03*
X316419Y106482D03*
X336419D03*
X316419Y146482D03*
X336419D03*
X347898Y117436D03*
X296419Y186482D03*
X295500Y169000D03*
X297398Y206436D03*
X317500Y186500D03*
X336419Y186482D03*
X317000Y166500D03*
X338500Y166000D03*
X317398Y206436D03*
X337398D03*
X297398Y226936D03*
Y246936D03*
Y266936D03*
X317398Y226936D03*
X337398D03*
X317398Y246936D03*
X337398D03*
X317398Y266936D03*
X337398D03*
X300398Y286936D03*
X317398D03*
X337398D03*
X295330Y337964D03*
Y377964D03*
Y357964D03*
X315330Y337964D03*
X335330D03*
X315330Y377964D03*
X335330D03*
X315330Y357964D03*
X335330D03*
X295830Y442464D03*
X295330Y417964D03*
X315830Y442464D03*
X335830D03*
X315330Y417964D03*
X335330D03*
X299898Y465436D03*
X339898D03*
X319898D03*
X356419Y6482D03*
Y26482D03*
Y46482D03*
X376419Y6482D03*
Y26482D03*
X396419Y6482D03*
Y26482D03*
X376419Y46482D03*
X396419D03*
X365398Y35936D03*
X356419Y66482D03*
Y86482D03*
X376419Y66482D03*
X396419D03*
X376419Y86482D03*
X396419D03*
X356419Y126482D03*
Y106482D03*
Y146482D03*
X376419Y126482D03*
X396419D03*
X376419Y106482D03*
X396419D03*
X376419Y146482D03*
X396419D03*
X357500Y186500D03*
X354500Y166500D03*
X357398Y206436D03*
X376419Y186482D03*
X396419D03*
X380000Y166500D03*
X396419Y166482D03*
X377398Y206436D03*
X397398D03*
X357398Y226936D03*
Y246936D03*
Y266936D03*
X377398Y226936D03*
X397398D03*
X377398Y246936D03*
X397398D03*
X377398Y266936D03*
X397398D03*
X393241Y239988D03*
X357398Y286936D03*
X377398D03*
X397398D03*
X394022Y308262D03*
X355330Y337964D03*
Y377964D03*
Y357964D03*
X375330Y337964D03*
X395330D03*
X375330Y377964D03*
X395330D03*
X375330Y357964D03*
X395330D03*
X355830Y442464D03*
X355330Y417964D03*
X375830Y442464D03*
X395830D03*
X375330Y417964D03*
X395330D03*
X364398Y430936D03*
X399898Y465436D03*
X379898D03*
X359898D03*
X416419Y6482D03*
Y26482D03*
X436419Y6482D03*
X416419Y46482D03*
X436419D03*
X456419D03*
X416419Y66482D03*
X436419D03*
X456419D03*
X416419Y86482D03*
X436419D03*
X456419D03*
X416419Y126482D03*
X436419D03*
X456419D03*
X416419Y106482D03*
X436419D03*
X456419D03*
X416419Y146482D03*
X436419D03*
X456419D03*
X416500Y166000D03*
X417519Y174482D03*
Y170282D03*
X425919D03*
X421719D03*
Y174482D03*
X431100Y174500D03*
Y170300D03*
X439500D03*
Y174500D03*
X435300Y170300D03*
Y174500D03*
X444100D03*
Y170300D03*
X452500D03*
Y174500D03*
X448300Y170300D03*
Y174500D03*
X457100Y175000D03*
Y170800D03*
X461300D03*
Y175000D03*
X418300Y197500D03*
Y201700D03*
X422500D03*
X426700D03*
X422500Y197500D03*
X426700D03*
X431300D03*
Y201700D03*
X435500D03*
X439700D03*
X435500Y197500D03*
X439700D03*
X444800D03*
Y201700D03*
X449000D03*
X453200D03*
X449000Y197500D03*
X453200D03*
X457800D03*
Y201700D03*
X462000D03*
Y197500D03*
X425919Y174482D03*
X436500Y166000D03*
X456500Y166500D03*
X417398Y206436D03*
X437398D03*
X457398D03*
X417398Y226936D03*
X437398D03*
X457398D03*
X417398Y246936D03*
X437398D03*
X457398D03*
X437398Y266936D03*
X457398D03*
X418398D03*
X437398Y286936D03*
X457398D03*
X418398D03*
X415330Y337964D03*
X435398Y338436D03*
X455398D03*
X415330Y377964D03*
Y357964D03*
X435398Y358436D03*
Y378436D03*
X455398Y358436D03*
Y378436D03*
X435830Y442464D03*
X455830D03*
X435330Y417964D03*
X455330D03*
X415830Y442464D03*
X415330Y417964D03*
X459898Y465436D03*
X439898D03*
X419898D03*
X516419Y6482D03*
X476419Y46482D03*
X496419D03*
X516419D03*
Y66482D03*
X476419D03*
X496419D03*
X516419Y86482D03*
X496419D03*
X476419D03*
Y126482D03*
X516419D03*
X496419D03*
X516419Y106482D03*
X496419D03*
X476419D03*
X485443Y160670D03*
X481243D03*
X493843D03*
X489643D03*
X476419Y146482D03*
X516419D03*
X496419D03*
X519221Y160912D03*
X510821D03*
X506621D03*
X515021D03*
X465500Y170800D03*
Y175000D03*
X466200Y201700D03*
Y197500D03*
X485443Y164870D03*
X481243D03*
X493843D03*
X489643D03*
X477284Y174586D03*
X473084D03*
Y170386D03*
X477284D03*
X498395Y174685D03*
Y170485D03*
X492911Y206602D03*
X488711D03*
X492911Y210802D03*
X488711D03*
X484511D03*
Y206602D03*
X480311Y210802D03*
Y206602D03*
X498052Y200389D03*
Y196189D03*
X477087Y201172D03*
X472887D03*
X477087Y196972D03*
X472887D03*
X519221Y165112D03*
X510821D03*
X506621D03*
X515021D03*
X502595Y174685D03*
Y170485D03*
X506135Y210557D03*
X510335D03*
X514535D03*
X518735D03*
X506135Y206357D03*
X510335D03*
X514535D03*
X518735D03*
X502252Y200389D03*
Y196189D03*
X507398Y196436D03*
X497398Y226936D03*
X477398D03*
X520898Y228436D03*
X497398Y246936D03*
X477398D03*
Y266936D03*
X512500Y323000D03*
X492000Y321000D03*
X506500Y305500D03*
X520500Y331000D03*
X520381Y300757D03*
X495398Y338436D03*
X475398D03*
X495398Y358436D03*
Y378436D03*
X475398Y358436D03*
Y378436D03*
X485398Y372436D03*
X477000Y418000D03*
X499000Y418500D03*
X485510Y442620D03*
X505510D03*
X469046Y443685D03*
X509898Y431936D03*
X519898Y465436D03*
X499898D03*
X479898D03*
X533619Y6482D03*
Y26482D03*
Y46482D03*
X550819Y6482D03*
Y26482D03*
Y46482D03*
X568019Y6482D03*
Y26482D03*
Y46482D03*
X525898Y33436D03*
X573623Y66967D03*
X536419Y66482D03*
X556419D03*
X536419Y86482D03*
X556419D03*
X568691Y66413D03*
X576419Y106482D03*
Y126482D03*
X536419D03*
X556419D03*
X536419Y106482D03*
X556419D03*
X544476Y161322D03*
X531876D03*
X536076D03*
X540276D03*
X536419Y146482D03*
X556419D03*
X526398Y116936D03*
X544477Y210389D03*
X544476Y165522D03*
X536076D03*
X531876D03*
X540276D03*
X552924Y175124D03*
X548724D03*
Y170924D03*
X552924D03*
X527711Y175174D03*
X523511D03*
Y170974D03*
X527711D03*
X531877Y210389D03*
X536077D03*
X540277D03*
X531877Y206189D03*
X536077D03*
X540277D03*
X544477D03*
X527761Y200632D03*
X523561D03*
X527761Y196432D03*
X523561D03*
X553171Y200877D03*
X548971D03*
X553171Y196677D03*
X548971D03*
X543000Y197500D03*
X546600Y257971D03*
X540898Y228436D03*
X561500Y232000D03*
X557000Y231500D03*
X560500Y268000D03*
X534898Y261436D03*
X549500Y305500D03*
X543900Y314000D03*
X559996Y282972D03*
X561500Y298000D03*
X534000Y282000D03*
X537136Y326402D03*
X525161Y311000D03*
X577500Y305000D03*
X536398Y418936D03*
X634119Y26482D03*
X585219Y46482D03*
Y26482D03*
Y6482D03*
X602419Y26482D03*
Y6482D03*
X619619D03*
Y26482D03*
Y46482D03*
X634119D03*
Y6482D03*
X602419Y46482D03*
X628500Y104000D03*
X626500Y78500D03*
X611253Y65701D03*
X584543Y86671D03*
X611398Y86936D03*
X633753Y65701D03*
X633898Y86936D03*
X610000Y100000D03*
X612747Y93023D03*
X634000Y123500D03*
X607000D03*
X616000Y138000D03*
Y115500D03*
X594500Y117000D03*
X616000Y173500D03*
X615500Y199000D03*
X615898Y244436D03*
Y224436D03*
X615398Y266436D03*
X587500Y318500D03*
X600000Y298500D03*
X616498Y316236D03*
X615398Y284436D03*
X633398Y325436D03*
X630000Y345500D03*
X600000Y337500D03*
Y342000D03*
X595500D03*
Y337500D03*
X630000Y387500D03*
X579500Y333500D03*
X612798Y413000D03*
X610898Y425436D03*
Y445436D03*
X617798Y413000D03*
X632898Y404936D03*
Y444936D03*
Y424936D03*
X605398Y409436D03*
X610898Y465436D03*
X632898Y464936D03*
G54D23*
G01X16751Y-179426D02*
Y-161926D01*
G01X25047D02*
X16751Y-172718D01*
G01X26357Y-179426D02*
X20462Y-167760D01*
G01X34032Y-179426D02*
Y-161926D01*
X44076Y-179426D01*
Y-161926D01*
G01X56554Y-179426D02*
X54807Y-179134D01*
X53279Y-177968D01*
X51969Y-176218D01*
X51095Y-174176D01*
X50659Y-171843D01*
Y-169509D01*
X51095Y-167176D01*
X51969Y-165134D01*
X53279Y-163385D01*
X54807Y-162218D01*
X56554Y-161926D01*
X58300Y-162218D01*
X59829Y-163385D01*
X61139Y-165134D01*
X62013Y-167176D01*
X62449Y-169509D01*
Y-171843D01*
X62013Y-174176D01*
X61139Y-176218D01*
X59829Y-177968D01*
X58300Y-179134D01*
X56554Y-179426D01*
G01X69469D02*
X78639Y-161926D01*
G01X69469D02*
X78639Y-179426D01*
G01X104687D02*
Y-161926D01*
X109927D01*
X111674Y-162801D01*
X112984Y-164843D01*
X113421Y-167176D01*
X112984Y-169509D01*
X111892Y-171259D01*
X109927Y-172135D01*
X104687D01*
G01X126554Y-179426D02*
X124807Y-179134D01*
X123279Y-177968D01*
X121969Y-176218D01*
X121095Y-174176D01*
X120659Y-171843D01*
Y-169509D01*
X121095Y-167176D01*
X121969Y-165134D01*
X123279Y-163385D01*
X124807Y-162218D01*
X126554Y-161926D01*
X128300Y-162218D01*
X129829Y-163385D01*
X131139Y-165134D01*
X132013Y-167176D01*
X132449Y-169509D01*
Y-171843D01*
X132013Y-174176D01*
X131139Y-176218D01*
X129829Y-177968D01*
X128300Y-179134D01*
X126554Y-179426D01*
G01X137504Y-161926D02*
X140560Y-179426D01*
X144054Y-161926D01*
X147547Y-179426D01*
X150604Y-161926D01*
G01X165921Y-179426D02*
X157187D01*
Y-161926D01*
X165921D01*
G01X162427Y-170384D02*
X157187D01*
G01X174687Y-179426D02*
Y-161926D01*
X180146D01*
X181892Y-162801D01*
X182984Y-163968D01*
X183421Y-166301D01*
X182984Y-168635D01*
X181674Y-170093D01*
X180146Y-170968D01*
X174687D01*
G01X180146D02*
X183421Y-179426D01*
G01X214054Y-161926D02*
Y-179426D01*
G01X209032Y-161926D02*
X219076D01*
G01X227187Y-179426D02*
Y-161926D01*
X232646D01*
X234392Y-162801D01*
X235484Y-163968D01*
X235921Y-166301D01*
X235484Y-168635D01*
X234174Y-170093D01*
X232646Y-170968D01*
X227187D01*
G01X232646D02*
X235921Y-179426D01*
G01X243595D02*
X249054Y-161926D01*
X254513Y-179426D01*
G01X252547Y-173301D02*
X245560D01*
G01X261532Y-179426D02*
Y-161926D01*
X271576Y-179426D01*
Y-161926D01*
G01X279469Y-177093D02*
X281216Y-178551D01*
X283181Y-179426D01*
X284927D01*
X286674Y-178551D01*
X287984Y-177093D01*
X288639Y-175051D01*
X288202Y-173010D01*
X287111Y-171259D01*
X285146Y-170093D01*
X282526Y-169509D01*
X280997Y-168343D01*
X280342Y-166301D01*
X280779Y-164259D01*
X281871Y-162801D01*
X283399Y-161926D01*
X284927D01*
X286456Y-162509D01*
X287766Y-163968D01*
G01X298934Y-161926D02*
X304174D01*
G01X301554D02*
Y-179426D01*
G01X298934D02*
X304174D01*
G01X319054Y-161926D02*
Y-179426D01*
G01X314032Y-161926D02*
X324076D01*
G01X333934D02*
X339174D01*
G01X336554D02*
Y-179426D01*
G01X333934D02*
X339174D01*
G01X354054D02*
X352307Y-179134D01*
X350779Y-177968D01*
X349469Y-176218D01*
X348595Y-174176D01*
X348159Y-171843D01*
Y-169509D01*
X348595Y-167176D01*
X349469Y-165134D01*
X350779Y-163385D01*
X352307Y-162218D01*
X354054Y-161926D01*
X355800Y-162218D01*
X357329Y-163385D01*
X358639Y-165134D01*
X359513Y-167176D01*
X359949Y-169509D01*
Y-171843D01*
X359513Y-174176D01*
X358639Y-176218D01*
X357329Y-177968D01*
X355800Y-179134D01*
X354054Y-179426D01*
G01X366532D02*
Y-161926D01*
X376576Y-179426D01*
Y-161926D01*
G01X408300Y-170093D02*
X409174Y-169218D01*
X409829Y-167760D01*
X410266Y-165717D01*
X409829Y-163968D01*
X408956Y-162801D01*
X407427Y-161926D01*
X401532D01*
Y-179426D01*
X408737D01*
X410266Y-178260D01*
X411139Y-176509D01*
X411576Y-174468D01*
X411139Y-172426D01*
X409829Y-170676D01*
X408300Y-170093D01*
X401532D01*
G01X424054Y-179426D02*
X422307Y-179134D01*
X420779Y-177968D01*
X419469Y-176218D01*
X418595Y-174176D01*
X418159Y-171843D01*
Y-169509D01*
X418595Y-167176D01*
X419469Y-165134D01*
X420779Y-163385D01*
X422307Y-162218D01*
X424054Y-161926D01*
X425800Y-162218D01*
X427329Y-163385D01*
X428639Y-165134D01*
X429513Y-167176D01*
X429949Y-169509D01*
Y-171843D01*
X429513Y-174176D01*
X428639Y-176218D01*
X427329Y-177968D01*
X425800Y-179134D01*
X424054Y-179426D01*
G01X436095D02*
X441554Y-161926D01*
X447013Y-179426D01*
G01X445047Y-173301D02*
X438060D01*
G01X454687Y-179426D02*
Y-161926D01*
X460146D01*
X461892Y-162801D01*
X462984Y-163968D01*
X463421Y-166301D01*
X462984Y-168635D01*
X461674Y-170093D01*
X460146Y-170968D01*
X454687D01*
G01X460146D02*
X463421Y-179426D01*
G01X471751D02*
Y-161926D01*
X476117D01*
X477864Y-162801D01*
X479174Y-163968D01*
X480266Y-165717D01*
X481139Y-167760D01*
X481357Y-170676D01*
X481139Y-173593D01*
X480266Y-175635D01*
X479174Y-177385D01*
X477864Y-178551D01*
X476117Y-179426D01*
X471751D01*
G01X208377Y-134426D02*
Y-116926D01*
X214054Y-131509D01*
X219731Y-116926D01*
Y-134426D01*
G01X231554D02*
X230244Y-134134D01*
X228934Y-132968D01*
X228060Y-130926D01*
X227624Y-128593D01*
X228060Y-126259D01*
X228934Y-124218D01*
X230244Y-123051D01*
X231554Y-122760D01*
X232864Y-123051D01*
X234174Y-124218D01*
X235047Y-126259D01*
X235266Y-128593D01*
X235047Y-130926D01*
X234174Y-132968D01*
X232864Y-134134D01*
X231554Y-134426D01*
G01X252984Y-116926D02*
Y-134426D01*
G01Y-131802D02*
X252111Y-133260D01*
X250800Y-134134D01*
X249272Y-134426D01*
X247526Y-133843D01*
X246216Y-132385D01*
X245342Y-130635D01*
X245124Y-128593D01*
X245342Y-126551D01*
X246216Y-124801D01*
X247526Y-123343D01*
X249272Y-122760D01*
X250800Y-123051D01*
X251892Y-123635D01*
X252984Y-124801D01*
G01X263279Y-126551D02*
X270266D01*
X269611Y-124509D01*
X268519Y-123343D01*
X266991Y-122760D01*
X265462Y-123051D01*
X264152Y-123926D01*
X263279Y-125968D01*
X262842Y-127718D01*
Y-129468D01*
X263279Y-131218D01*
X264371Y-132968D01*
X265681Y-134134D01*
X267209Y-134426D01*
X268737Y-133843D01*
X270266Y-132093D01*
G01X284054Y-134426D02*
Y-116926D01*
G01X536554Y-179426D02*
Y-161926D01*
X533934Y-165426D01*
G01Y-179426D02*
X539174D01*
G01X549906Y-164843D02*
X551216Y-163093D01*
X552744Y-162218D01*
X554491Y-161926D01*
X556674Y-162509D01*
X558202Y-163968D01*
X558639Y-165717D01*
X558421Y-167468D01*
X557547Y-168926D01*
X553181Y-171843D01*
X551216Y-173884D01*
X549906Y-176802D01*
X549469Y-179426D01*
X558639D01*
G01X566751Y-176802D02*
X568060Y-178260D01*
X569589Y-179134D01*
X571554Y-179426D01*
X573519Y-178843D01*
X575047Y-177676D01*
X576139Y-175635D01*
X576357Y-173301D01*
X575921Y-170968D01*
X574829Y-169509D01*
X573300Y-168343D01*
X571772Y-168051D01*
X570244Y-168343D01*
X568279Y-169509D01*
X568934Y-161926D01*
X574829D01*
G01X584906Y-164843D02*
X586216Y-163093D01*
X587744Y-162218D01*
X589491Y-161926D01*
X591674Y-162509D01*
X593202Y-163968D01*
X593639Y-165717D01*
X593421Y-167468D01*
X592547Y-168926D01*
X588181Y-171843D01*
X586216Y-173884D01*
X584906Y-176802D01*
X584469Y-179426D01*
X593639D01*
G01X601751Y-175926D02*
X603060Y-177968D01*
X604807Y-179134D01*
X606772Y-179426D01*
X608519Y-179134D01*
X610266Y-177676D01*
X611357Y-175926D01*
X611576Y-174176D01*
X611139Y-172135D01*
X609611Y-170676D01*
X608082Y-170093D01*
X606117D01*
G01X608082D02*
X609392Y-169218D01*
X610484Y-167760D01*
X610921Y-166010D01*
X610484Y-164259D01*
X609392Y-162801D01*
X607427Y-161926D01*
X605462Y-162218D01*
X603497Y-163385D01*
G01X523437Y-134426D02*
Y-116926D01*
X528677D01*
X530424Y-117801D01*
X531734Y-119843D01*
X532171Y-122176D01*
X531734Y-124509D01*
X530642Y-126259D01*
X528677Y-127135D01*
X523437D01*
G01X550107Y-118385D02*
X548797Y-117509D01*
X547269Y-116926D01*
X545522D01*
X543557Y-117801D01*
X542029Y-119259D01*
X540937Y-121010D01*
X540064Y-123926D01*
X539845Y-126551D01*
X540282Y-129176D01*
X540937Y-130926D01*
X542247Y-132676D01*
X543776Y-133843D01*
X545304Y-134426D01*
X546832D01*
X548361Y-133843D01*
X549671Y-132968D01*
X550763Y-131802D01*
G01X564550Y-125093D02*
X565424Y-124218D01*
X566079Y-122760D01*
X566516Y-120717D01*
X566079Y-118968D01*
X565206Y-117801D01*
X563677Y-116926D01*
X557782D01*
Y-134426D01*
X564987D01*
X566516Y-133260D01*
X567389Y-131509D01*
X567826Y-129468D01*
X567389Y-127426D01*
X566079Y-125676D01*
X564550Y-125093D01*
X557782D01*
G01X573754Y-140259D02*
X586854D01*
G01X592782Y-134426D02*
Y-116926D01*
X602826Y-134426D01*
Y-116926D01*
G01X615304Y-134426D02*
X613557Y-134134D01*
X612029Y-132968D01*
X610719Y-131218D01*
X609845Y-129176D01*
X609409Y-126843D01*
Y-124509D01*
X609845Y-122176D01*
X610719Y-120134D01*
X612029Y-118385D01*
X613557Y-117218D01*
X615304Y-116926D01*
X617050Y-117218D01*
X618579Y-118385D01*
X619889Y-120134D01*
X620763Y-122176D01*
X621199Y-124509D01*
Y-126843D01*
X620763Y-129176D01*
X619889Y-131218D01*
X618579Y-132968D01*
X617050Y-134134D01*
X615304Y-134426D01*
G01X697854Y-179426D02*
Y-161926D01*
X695234Y-165426D01*
G01Y-179426D02*
X700474D01*
G01X666145Y-116926D02*
X671604Y-134426D01*
X677063Y-116926D01*
G01X693471Y-134426D02*
X684737D01*
Y-116926D01*
X693471D01*
G01X689977Y-125384D02*
X684737D01*
G01X702237Y-134426D02*
Y-116926D01*
X707696D01*
X709442Y-117801D01*
X710534Y-118968D01*
X710971Y-121301D01*
X710534Y-123635D01*
X709224Y-125093D01*
X707696Y-125968D01*
X702237D01*
G01X707696D02*
X710971Y-134426D01*
G01X724104Y-135009D02*
X723667Y-134718D01*
Y-134134D01*
X724104Y-133843D01*
X724541Y-134134D01*
Y-134718D01*
X724104Y-135009D01*
G01X790937Y-116926D02*
Y-134426D01*
X799671D01*
G01X816734D02*
Y-122760D01*
G01Y-124801D02*
X815861Y-123635D01*
X814550Y-123051D01*
X813022Y-122760D01*
X811494Y-123343D01*
X810184Y-124509D01*
X809310Y-126259D01*
X808874Y-128593D01*
X809310Y-130926D01*
X810184Y-132676D01*
X811494Y-133843D01*
X813022Y-134426D01*
X814550Y-134134D01*
X815861Y-133260D01*
X816734Y-132093D01*
G01X825719Y-139676D02*
X827029Y-140259D01*
X828776Y-139676D01*
X829867Y-138510D01*
X830741Y-137051D01*
X832050Y-132385D01*
X834889Y-122760D01*
G01X827902D02*
X832050Y-132385D01*
G01X844529Y-126551D02*
X851516D01*
X850861Y-124509D01*
X849769Y-123343D01*
X848241Y-122760D01*
X846712Y-123051D01*
X845402Y-123926D01*
X844529Y-125968D01*
X844092Y-127718D01*
Y-129468D01*
X844529Y-131218D01*
X845621Y-132968D01*
X846931Y-134134D01*
X848459Y-134426D01*
X849987Y-133843D01*
X851516Y-132093D01*
G01X862247Y-134426D02*
Y-122760D01*
G01Y-125093D02*
X863339Y-123926D01*
X864431Y-123051D01*
X865959Y-122760D01*
X867050Y-123051D01*
X868361Y-123926D01*
G01X879529Y-132385D02*
X880621Y-133551D01*
X882149Y-134426D01*
X883459D01*
X884769Y-133843D01*
X885642Y-132968D01*
X886079Y-131802D01*
X885861Y-130051D01*
X884987Y-129176D01*
X881057Y-127426D01*
X880184Y-125384D01*
X880621Y-123926D01*
X881494Y-123051D01*
X882804Y-122760D01*
X884114Y-123051D01*
X885424Y-123926D01*
G01X852171Y-161926D02*
Y-179426D01*
X843437D01*
G01X827684D02*
Y-161926D01*
X835763Y-174468D01*
X824845D01*
G01X924737Y-175926D02*
X925829Y-177676D01*
X927139Y-178843D01*
X928667Y-179426D01*
X930414Y-178843D01*
X931724Y-177676D01*
X933034Y-175926D01*
X933471Y-173593D01*
Y-161926D01*
G01X946604Y-179426D02*
X944857Y-179134D01*
X943329Y-177968D01*
X942019Y-176218D01*
X941145Y-174176D01*
X940709Y-171843D01*
Y-169509D01*
X941145Y-167176D01*
X942019Y-165134D01*
X943329Y-163385D01*
X944857Y-162218D01*
X946604Y-161926D01*
X948350Y-162218D01*
X949879Y-163385D01*
X951189Y-165134D01*
X952063Y-167176D01*
X952499Y-169509D01*
Y-171843D01*
X952063Y-174176D01*
X951189Y-176218D01*
X949879Y-177968D01*
X948350Y-179134D01*
X946604Y-179426D01*
G01X959519Y-177093D02*
X961266Y-178551D01*
X963231Y-179426D01*
X964977D01*
X966724Y-178551D01*
X968034Y-177093D01*
X968689Y-175051D01*
X968252Y-173010D01*
X967161Y-171259D01*
X965196Y-170093D01*
X962576Y-169509D01*
X961047Y-168343D01*
X960392Y-166301D01*
X960829Y-164259D01*
X961921Y-162801D01*
X963449Y-161926D01*
X964977D01*
X966506Y-162509D01*
X967816Y-163968D01*
G01X985971Y-179426D02*
X977237D01*
Y-161926D01*
X985971D01*
G01X982477Y-170384D02*
X977237D01*
G01X994737Y-179426D02*
Y-161926D01*
X999977D01*
X1001724Y-162801D01*
X1003034Y-164843D01*
X1003471Y-167176D01*
X1003034Y-169509D01*
X1001942Y-171259D01*
X999977Y-172135D01*
X994737D01*
G01X1012019Y-179426D02*
Y-161926D01*
G01X1021189D02*
Y-179426D01*
G01Y-170676D02*
X1012019D01*
G01X1047237Y-161926D02*
Y-179426D01*
X1055971D01*
G01X1063645D02*
X1069104Y-161926D01*
X1074563Y-179426D01*
G01X1072597Y-173301D02*
X1065610D01*
G01X1081801Y-161926D02*
Y-174468D01*
X1082674Y-177093D01*
X1084421Y-178843D01*
X1086604Y-179426D01*
X1088787Y-178843D01*
X1090534Y-177093D01*
X1091407Y-174468D01*
Y-161926D01*
G01X941801Y-134426D02*
Y-116926D01*
X946167D01*
X947914Y-117801D01*
X949224Y-118968D01*
X950316Y-120717D01*
X951189Y-122760D01*
X951407Y-125676D01*
X951189Y-128593D01*
X950316Y-130635D01*
X949224Y-132385D01*
X947914Y-133551D01*
X946167Y-134426D01*
X941801D01*
G01X960829Y-126551D02*
X967816D01*
X967161Y-124509D01*
X966069Y-123343D01*
X964541Y-122760D01*
X963012Y-123051D01*
X961702Y-123926D01*
X960829Y-125968D01*
X960392Y-127718D01*
Y-129468D01*
X960829Y-131218D01*
X961921Y-132968D01*
X963231Y-134134D01*
X964759Y-134426D01*
X966287Y-133843D01*
X967816Y-132093D01*
G01X978329Y-132385D02*
X979421Y-133551D01*
X980949Y-134426D01*
X982259D01*
X983569Y-133843D01*
X984442Y-132968D01*
X984879Y-131802D01*
X984661Y-130051D01*
X983787Y-129176D01*
X979857Y-127426D01*
X978984Y-125384D01*
X979421Y-123926D01*
X980294Y-123051D01*
X981604Y-122760D01*
X982914Y-123051D01*
X984224Y-123926D01*
G01X999104Y-122760D02*
Y-134426D01*
G01Y-118093D02*
X998667Y-117801D01*
Y-117218D01*
X999104Y-116926D01*
X999541Y-117218D01*
Y-117801D01*
X999104Y-118093D01*
G01X1013547Y-138801D02*
X1015076Y-139968D01*
X1016822Y-140259D01*
X1018350Y-139968D01*
X1019661Y-138510D01*
X1020534Y-136468D01*
Y-122760D01*
G01Y-125093D02*
X1019661Y-123926D01*
X1018350Y-123051D01*
X1016822Y-122760D01*
X1015076Y-123343D01*
X1013984Y-124509D01*
X1013110Y-126551D01*
X1012674Y-128593D01*
X1012892Y-130343D01*
X1013766Y-132385D01*
X1015076Y-133843D01*
X1016822Y-134426D01*
X1018132Y-134134D01*
X1019661Y-132968D01*
X1020534Y-131802D01*
G01X1030392Y-134426D02*
Y-122760D01*
G01Y-125676D02*
X1031266Y-124218D01*
X1032576Y-123051D01*
X1034322Y-122760D01*
X1035850Y-123051D01*
X1037161Y-124218D01*
X1037816Y-126259D01*
Y-134426D01*
G01X1048329Y-126551D02*
X1055316D01*
X1054661Y-124509D01*
X1053569Y-123343D01*
X1052041Y-122760D01*
X1050512Y-123051D01*
X1049202Y-123926D01*
X1048329Y-125968D01*
X1047892Y-127718D01*
Y-129468D01*
X1048329Y-131218D01*
X1049421Y-132968D01*
X1050731Y-134134D01*
X1052259Y-134426D01*
X1053787Y-133843D01*
X1055316Y-132093D01*
G01X1066047Y-134426D02*
Y-122760D01*
G01Y-125093D02*
X1067139Y-123926D01*
X1068231Y-123051D01*
X1069759Y-122760D01*
X1070850Y-123051D01*
X1072161Y-123926D01*
G01X1112804Y-179426D02*
Y-161926D01*
X1110184Y-165426D01*
G01Y-179426D02*
X1115424D01*
G01X1130304Y-161926D02*
X1128557Y-162509D01*
X1127247Y-163968D01*
X1126374Y-165717D01*
X1125719Y-168051D01*
X1125501Y-170676D01*
X1125719Y-173301D01*
X1126374Y-175635D01*
X1127247Y-177385D01*
X1128557Y-178843D01*
X1130304Y-179426D01*
X1132050Y-178843D01*
X1133361Y-177385D01*
X1134234Y-175635D01*
X1134889Y-173301D01*
X1135107Y-170676D01*
X1134889Y-168051D01*
X1134234Y-165717D01*
X1133361Y-163968D01*
X1132050Y-162509D01*
X1130304Y-161926D01*
G01X1143874Y-180009D02*
X1151734Y-161926D01*
G01X1165304Y-179426D02*
Y-161926D01*
X1162684Y-165426D01*
G01Y-179426D02*
X1167924D01*
G01X1179092Y-177385D02*
X1180621Y-178843D01*
X1182367Y-179426D01*
X1184114Y-178843D01*
X1185642Y-177093D01*
X1186734Y-174468D01*
X1187171Y-171843D01*
Y-168635D01*
X1186734Y-166010D01*
X1185642Y-163676D01*
X1184332Y-162509D01*
X1182804Y-161926D01*
X1181057Y-162509D01*
X1179747Y-163676D01*
X1178874Y-165426D01*
X1178437Y-167760D01*
X1178874Y-169801D01*
X1179966Y-171843D01*
X1181276Y-173010D01*
X1182804Y-173301D01*
X1184550Y-172718D01*
X1185861Y-171259D01*
X1187171Y-168635D01*
G01X1196374Y-180009D02*
X1204234Y-161926D01*
G01X1213656Y-164843D02*
X1214966Y-163093D01*
X1216494Y-162218D01*
X1218241Y-161926D01*
X1220424Y-162509D01*
X1221952Y-163968D01*
X1222389Y-165717D01*
X1222171Y-167468D01*
X1221297Y-168926D01*
X1216931Y-171843D01*
X1214966Y-173884D01*
X1213656Y-176802D01*
X1213219Y-179426D01*
X1222389D01*
G01X1235304Y-161926D02*
X1233557Y-162509D01*
X1232247Y-163968D01*
X1231374Y-165717D01*
X1230719Y-168051D01*
X1230501Y-170676D01*
X1230719Y-173301D01*
X1231374Y-175635D01*
X1232247Y-177385D01*
X1233557Y-178843D01*
X1235304Y-179426D01*
X1237050Y-178843D01*
X1238361Y-177385D01*
X1239234Y-175635D01*
X1239889Y-173301D01*
X1240107Y-170676D01*
X1239889Y-168051D01*
X1239234Y-165717D01*
X1238361Y-163968D01*
X1237050Y-162509D01*
X1235304Y-161926D01*
G01X1252804Y-179426D02*
Y-161926D01*
X1250184Y-165426D01*
G01Y-179426D02*
X1255424D01*
G01X1266156Y-164843D02*
X1267466Y-163093D01*
X1268994Y-162218D01*
X1270741Y-161926D01*
X1272924Y-162509D01*
X1274452Y-163968D01*
X1274889Y-165717D01*
X1274671Y-167468D01*
X1273797Y-168926D01*
X1269431Y-171843D01*
X1267466Y-173884D01*
X1266156Y-176802D01*
X1265719Y-179426D01*
X1274889D01*
G01X1160501Y-134426D02*
Y-116926D01*
X1164867D01*
X1166614Y-117801D01*
X1167924Y-118968D01*
X1169016Y-120717D01*
X1169889Y-122760D01*
X1170107Y-125676D01*
X1169889Y-128593D01*
X1169016Y-130635D01*
X1167924Y-132385D01*
X1166614Y-133551D01*
X1164867Y-134426D01*
X1160501D01*
G01X1186734D02*
Y-122760D01*
G01Y-124801D02*
X1185861Y-123635D01*
X1184550Y-123051D01*
X1183022Y-122760D01*
X1181494Y-123343D01*
X1180184Y-124509D01*
X1179310Y-126259D01*
X1178874Y-128593D01*
X1179310Y-130926D01*
X1180184Y-132676D01*
X1181494Y-133843D01*
X1183022Y-134426D01*
X1184550Y-134134D01*
X1185861Y-133260D01*
X1186734Y-132093D01*
G01X1200304Y-116926D02*
Y-134426D01*
G01X1197247Y-122760D02*
X1203361D01*
G01X1214529Y-126551D02*
X1221516D01*
X1220861Y-124509D01*
X1219769Y-123343D01*
X1218241Y-122760D01*
X1216712Y-123051D01*
X1215402Y-123926D01*
X1214529Y-125968D01*
X1214092Y-127718D01*
Y-129468D01*
X1214529Y-131218D01*
X1215621Y-132968D01*
X1216931Y-134134D01*
X1218459Y-134426D01*
X1219987Y-133843D01*
X1221516Y-132093D01*
G54D14*
X-22005Y124122D03*
Y133422D03*
Y142722D03*
Y164122D03*
Y173422D03*
Y182722D03*
Y204122D03*
Y213422D03*
Y222722D03*
Y244122D03*
Y253422D03*
Y262722D03*
Y283072D03*
G54D24*
G01X-26055Y322202D02*
X-8000D01*
X-702Y329500D01*
X19000D01*
X19936Y330436D01*
X26500D01*
G01X-26055Y327202D02*
X-15642D01*
X-12392Y330452D01*
X-5500D01*
X-3952Y332000D01*
X10000D01*
G01X-26055Y317202D02*
X-16907D01*
X-14609Y319500D01*
X-6936D01*
X500Y326936D01*
X3398D01*
G01X-26055Y332202D02*
X-6336D01*
X-2538Y336000D01*
X14000D01*
G01X1494Y343705D02*
X-1211Y341000D01*
X-2722D01*
G01X-26055Y342202D02*
X-12500D01*
X-11298Y341000D01*
X-2722D01*
G01X5694Y343705D02*
X1635Y347764D01*
G01X-26055Y352202D02*
X-2803D01*
X1635Y347764D01*
G01X30923Y335665D02*
Y332169D01*
X29190Y330436D01*
X26500D01*
G01X26723Y335665D02*
X26388Y336000D01*
X14000D01*
G01X561500Y232000D02*
Y233500D01*
X566250Y238250D01*
X576868D01*
X580709Y234409D01*
G01X557000Y231500D02*
X565500Y240000D01*
X576300D01*
X580709Y244409D01*
G01Y204409D02*
X584800Y208500D01*
X606000D01*
X611000Y203500D01*
Y101000D01*
X610000Y100000D01*
G01X580709Y214409D02*
X584618Y210500D01*
X607500D01*
X612750Y205250D01*
Y93026D01*
X612747Y93023D01*
G01X596102Y82677D02*
X599177D01*
X610000Y93500D01*
Y100000D01*
G01X602008Y74803D02*
Y81495D01*
X612747Y92234D01*
Y93023D01*
G54D15*
X-25005Y133422D03*
Y173422D03*
Y213422D03*
Y253422D03*
G54D16*
Y283072D03*
G54D17*
X-27555Y302202D03*
Y307202D03*
Y312202D03*
Y317202D03*
Y322202D03*
Y327202D03*
Y332202D03*
Y337202D03*
Y342202D03*
Y347202D03*
Y352202D03*
Y357202D03*
G54D18*
X570709Y161889D03*
X580709D03*
X570709Y214409D03*
X580709D03*
X570709Y204409D03*
X580709D03*
X570709Y191889D03*
X580709D03*
X570709Y181889D03*
X580709D03*
X570709Y171889D03*
X580709D03*
X570709Y244409D03*
X580709D03*
X570709Y276929D03*
X580709D03*
X570709Y266929D03*
X580709D03*
X570709Y256929D03*
X580709D03*
X570709Y234409D03*
X580709D03*
X570709Y224409D03*
X580709D03*
X570709Y286929D03*
X580709D03*
X590709Y161889D03*
X600709D03*
X590709Y214409D03*
X600709D03*
X590709Y204409D03*
X600709D03*
X590709Y191889D03*
X600709D03*
X590709Y181889D03*
X600709D03*
X590709Y171889D03*
X600709D03*
X590709Y244409D03*
X600709D03*
X590709Y276929D03*
X600709D03*
X590709Y266929D03*
X600709D03*
X590709Y256929D03*
X600709D03*
X590709Y234409D03*
X600709D03*
X590709Y224409D03*
X600709D03*
X590709Y286929D03*
X600709D03*
G54D19*
X596102Y66929D03*
X602008Y74803D03*
X596102Y82677D03*
M02*
